(kicad_pcb
	(version 20260206)
	(generator "pcbnew")
	(generator_version "10.0")
	(general
		(thickness 1.6)
		(legacy_teardrops no)
	)
	(paper "A4")
	(title_block
		(title "Wiwynn_Tioga_Pass_MB.brd")
		(comment 1 "Tioga Pass / footprints 1018-1023 of 4770")
	)
	(layers
		(0 "F.Cu" signal "TOP")
		(4 "In1.Cu" signal "L2GND")
		(6 "In2.Cu" signal "L3")
		(8 "In3.Cu" signal "L4GND")
		(10 "In4.Cu" signal "L5")
		(12 "In5.Cu" signal "L6GND")
		(14 "In6.Cu" signal "L7VCC")
		(16 "In7.Cu" signal "L8VCC")
		(18 "In8.Cu" signal "L9GND")
		(20 "In9.Cu" signal "L10")
		(22 "In10.Cu" signal "L11GND")
		(24 "In11.Cu" signal "L12")
		(26 "In12.Cu" signal "L13GND")
		(2 "B.Cu" signal "BOTTOM")
		(9 "F.Adhes" user "F.Adhesive")
		(11 "B.Adhes" user "B.Adhesive")
		(13 "F.Paste" user "Package Geometry/Pastemask Top")
		(15 "B.Paste" user "Package Geometry/Pastemask Bottom")
		(5 "F.SilkS" user "Ref Des/Silkscreen Top")
		(7 "B.SilkS" user "Ref Des/Silkscreen Bottom")
		(1 "F.Mask" user "Board Geometry/Soldermask Top")
		(3 "B.Mask" user "Board Geometry/Soldermask Bottom")
		(17 "Dwgs.User" user "User.Drawings")
		(19 "Cmts.User" user "User.Comments")
		(21 "Eco1.User" user "User.Eco1")
		(23 "Eco2.User" user "User.Eco2")
		(25 "Edge.Cuts" user "Board Geometry/Outline")
		(27 "Margin" user)
		(31 "F.CrtYd" user "Package Geometry/Place Bound Top")
		(29 "B.CrtYd" user "Package Geometry/Place Bound Bottom")
		(35 "F.Fab" user "Ref Des/Assembly Top")
		(33 "B.Fab" user "Ref Des/Assembly Bottom")
	)
	(footprint ""
		(layer "F.Cu")
		(at 33.925002 -65.167764 90)
		(property "Reference" "EU1D4"
			(at 3.334766 -1.844802 0)
			(unlocked yes)
			(layer "F.SilkS")
			(effects
				(font
					(size 0.7874 0.5842)
					(thickness 0.1524)
				)
			)
		)
		(property "Value" ""
			(at 0 0 90)
			(layer "F.Fab")
			(effects
				(font
					(size 1.27 1.27)
				)
			)
		)
		(duplicate_pad_numbers_are_jumpers no)
		(fp_line
			(start 2.9718 -3.5052)
			(end 2.9718 3.429)
			(stroke
				(width 0.1524)
				(type default)
			)
			(layer "F.SilkS")
		)
		(fp_line
			(start -3.0099 -3.5052)
			(end 2.9718 -3.5052)
			(stroke
				(width 0.1524)
				(type default)
			)
			(layer "F.SilkS")
		)
		(fp_line
			(start 2.9718 3.429)
			(end -3.0099 3.429)
			(stroke
				(width 0.1524)
				(type default)
			)
			(layer "F.SilkS")
		)
		(fp_line
			(start -3.0099 3.429)
			(end -3.0099 -3.5052)
			(stroke
				(width 0.1524)
				(type default)
			)
			(layer "F.SilkS")
		)
		(fp_circle
			(center -3.057398 -2.678684)
			(end -3.057398 -2.551684)
			(stroke
				(width 0.254)
				(type default)
			)
			(fill no)
			(layer "F.SilkS")
		)
		(fp_poly
			(pts
				(xy -2.9972 -3.4925) (xy -2.9972 -2.6924) (xy -2.1971 -3.4925)
			)
			(stroke
				(width 0)
				(type default)
			)
			(fill yes)
			(layer "F.SilkS")
		)
		(fp_poly
			(pts
				(xy -2.549906 -3.050032) (xy -2.549906 3.050032) (xy 2.549906 3.050032) (xy 2.549906 -3.050032)
			)
			(stroke
				(width 0)
				(type default)
			)
			(fill no)
			(layer "F.CrtYd")
		)
		(fp_line
			(start 2.549906 -3.050032)
			(end 2.549906 3.050032)
			(stroke
				(width 0.1)
				(type default)
			)
			(layer "F.Fab")
		)
		(fp_line
			(start -2.549906 -3.050032)
			(end 2.549906 -3.050032)
			(stroke
				(width 0.1)
				(type default)
			)
			(layer "F.Fab")
		)
		(fp_line
			(start 2.549906 3.050032)
			(end -2.549906 3.050032)
			(stroke
				(width 0.1)
				(type default)
			)
			(layer "F.Fab")
		)
		(fp_line
			(start -2.549906 3.050032)
			(end -2.549906 -3.050032)
			(stroke
				(width 0.1)
				(type default)
			)
			(layer "F.Fab")
		)
		(fp_circle
			(center -3.057398 -2.678684)
			(end -3.057398 -2.551684)
			(stroke
				(width 0.254)
				(type default)
			)
			(fill no)
			(layer "F.Fab")
		)
		(pad "1" smd rect
			(at -2.39522 -2.279904 90)
			(size 0.7112 0.254)
			(layers "F.Cu" "F.Mask" "F.Paste")
			(net "PVCCIN_CPU1")
		)
		(pad "2" smd rect
			(at -2.39522 -1.83007 90)
			(size 0.7112 0.254)
			(layers "F.Cu" "F.Mask" "F.Paste")
			(net "GND")
		)
		(pad "3" smd rect
			(at -2.39522 -1.379982 90)
			(size 0.7112 0.254)
			(layers "F.Cu" "F.Mask" "F.Paste")
			(net "VR_PVCCIN_CPU1_PH2_VCIN")
		)
		(pad "4" smd rect
			(at -2.39522 -0.929894 90)
			(size 0.7112 0.254)
			(layers "F.Cu" "F.Mask" "F.Paste")
			(net "P5V_STBY")
		)
		(pad "5" smd rect
			(at -2.39522 -0.48006 90)
			(size 0.7112 0.254)
			(layers "F.Cu" "F.Mask" "F.Paste")
			(net "GND")
		)
		(pad "6" smd rect
			(at -2.39522 -0.029972 90)
			(size 0.7112 0.254)
			(layers "F.Cu" "F.Mask" "F.Paste")
			(net "TP_PVCCINC_CPU1_PH2_GL_0")
		)
		(pad "7" smd custom
			(at 0.016764 1.145032 90)
			(size 0.53975 0.53975)
			(layers "F.Cu" "F.Mask" "F.Paste")
			(net "GND")
			(options
				(clearance outline)
				(anchor circle)
			)
			(primitives
				(gr_poly
					(pts
						(xy -2.7051 1.0795) (xy -2.7051 -0.3683) (xy -0.9271 -0.3683) (xy -0.9271 -1.0795) (xy 2.7051 -1.0795)
						(xy 2.7051 1.0795)
					)
					(width 0)
					(fill yes)
				)
			)
		)
		(pad "10" smd rect
			(at -0.008382 2.874772 90)
			(size 4.3434 0.6096)
			(layers "F.Cu" "F.Mask" "F.Paste")
			(net "VR_PVCCIN_CPU1_PHASE2")
		)
		(pad "25" smd rect
			(at 1.548384 -1.283208 90)
			(size 2.3368 2.0066)
			(layers "F.Cu" "F.Mask" "F.Paste")
			(net "VR_FET_SW_P12V_STBY_PVCCIN_CPU1")
		)
		(pad "30" smd rect
			(at 2.050034 -2.895092 90)
			(size 0.254 0.7112)
			(layers "F.Cu" "F.Mask" "F.Paste")
			(net "VR_FET_SW_P12V_STBY_PVCCIN_CPU1")
		)
		(pad "31" smd rect
			(at 1.599946 -2.895092 90)
			(size 0.254 0.7112)
			(layers "F.Cu" "F.Mask" "F.Paste")
			(net "Net_357")
		)
		(pad "32" smd rect
			(at 1.150112 -2.895092 90)
			(size 0.254 0.7112)
			(layers "F.Cu" "F.Mask" "F.Paste")
			(net "VR_PVCCIN_CPU1_PH2_PHASE")
		)
		(pad "33" smd rect
			(at 0.700024 -2.895092 90)
			(size 0.254 0.7112)
			(layers "F.Cu" "F.Mask" "F.Paste")
			(net "VR_PVCCIN_CPU1_PH2_BOOT_R")
		)
		(pad "34" smd rect
			(at 0.249936 -2.895092 90)
			(size 0.254 0.7112)
			(layers "F.Cu" "F.Mask" "F.Paste")
			(net "VR_PVCCIN_CPU1_PWM2")
		)
		(pad "35" smd rect
			(at -0.199898 -2.895092 90)
			(size 0.254 0.7112)
			(layers "F.Cu" "F.Mask" "F.Paste")
			(net "P5V_STBY")
		)
		(pad "36" smd rect
			(at -0.649986 -2.895092 90)
			(size 0.254 0.7112)
			(layers "F.Cu" "F.Mask" "F.Paste")
			(net "A_TSENSE_PVCCIN_CPU1")
		)
		(pad "37" smd rect
			(at -1.100074 -2.895092 90)
			(size 0.254 0.7112)
			(layers "F.Cu" "F.Mask" "F.Paste")
			(net "VR_PVCCIN_CPU1_PH2_OCSET")
		)
		(pad "38" smd rect
			(at -1.549908 -2.895092 90)
			(size 0.254 0.7112)
			(layers "F.Cu" "F.Mask" "F.Paste")
			(net "ISENSE_PVCCIN_CPU1_PH2_IMON")
		)
		(pad "39" smd rect
			(at -1.999996 -2.895092 90)
			(size 0.254 0.7112)
			(layers "F.Cu" "F.Mask" "F.Paste")
			(net "VR_PVCCIN_CPU1_AIREF2")
		)
		(pad "40" smd rect
			(at -0.871728 -1.283208 90)
			(size 1.8034 2.0066)
			(layers "F.Cu" "F.Mask" "F.Paste")
			(net "GND")
		)
		(pad "41" smd rect
			(at -1.533906 0.247904 90)
			(size 0.508 0.3556)
			(layers "F.Cu" "F.Mask" "F.Paste")
			(net "TP_PVCCINC_CPU1_PH2_GL_1")
		)
	)
	(footprint ""
		(layer "F.Cu")
		(at 23.29434 -86.1568 180)
		(property "Reference" "RF7"
			(at -0.8382 -0.67818 180)
			(unlocked yes)
			(layer "F.SilkS")
			(effects
				(font
					(size 0.4064 0.254)
					(thickness 0.1524)
				)
				(justify left)
			)
		)
		(property "Value" ""
			(at 0 0 180)
			(layer "F.Fab")
			(effects
				(font
					(size 1.27 1.27)
				)
			)
		)
		(duplicate_pad_numbers_are_jumpers no)
		(fp_poly
			(pts
				(xy -0.2794 -0.1016) (xy 0.2794 -0.1016) (xy 0.2794 0.9906) (xy -0.2794 0.9906)
			)
			(stroke
				(width 0)
				(type default)
			)
			(fill no)
			(layer "F.CrtYd")
		)
		(fp_line
			(start 0.2794 0.9906)
			(end 0.2794 -0.1016)
			(stroke
				(width 0.1)
				(type default)
			)
			(layer "F.Fab")
		)
		(fp_line
			(start 0.2794 -0.1016)
			(end -0.2794 -0.1016)
			(stroke
				(width 0.1)
				(type default)
			)
			(layer "F.Fab")
		)
		(fp_line
			(start -0.2794 0.9906)
			(end 0.2794 0.9906)
			(stroke
				(width 0.1)
				(type default)
			)
			(layer "F.Fab")
		)
		(fp_line
			(start -0.2794 -0.1016)
			(end -0.2794 0.9906)
			(stroke
				(width 0.1)
				(type default)
			)
			(layer "F.Fab")
		)
		(pad "1" smd rect
			(at 0 0 180)
			(size 0.508 0.508)
			(layers "F.Cu" "F.Mask" "F.Paste")
			(net "VR_PVCCIN_CPU1_AIREF1")
		)
		(pad "2" smd rect
			(at 0 0.889 180)
			(size 0.508 0.508)
			(layers "F.Cu" "F.Mask" "F.Paste")
			(net "ISENSE_PVCCIN_CPU1_PH1_IMON")
		)
		(zone
			(layer "F.Cu")
			(hatch none 0.5)
			(connect_pads
				(clearance 0)
			)
			(min_thickness 0.25)
			(keepout
				(tracks not_allowed)
				(vias allowed)
				(pads allowed)
				(copperpour not_allowed)
				(footprints allowed)
			)
			(placement
				(enabled no)
				(sheetname "")
			)
			(fill
				(thermal_gap 0.5)
				(thermal_bridge_width 0.5)
				(island_removal_mode 0)
			)
			(polygon
				(pts
					(xy 23.54834 -86.7918) (xy 23.04034 -86.7918) (xy 23.04034 -86.4108) (xy 23.54834 -86.4108)
				)
			)
		)
		(zone
			(layer "F.Cu")
			(hatch none 0.5)
			(connect_pads
				(clearance 0)
			)
			(min_thickness 0.25)
			(keepout
				(tracks allowed)
				(vias not_allowed)
				(pads allowed)
				(copperpour not_allowed)
				(footprints allowed)
			)
			(placement
				(enabled no)
				(sheetname "")
			)
			(fill
				(thermal_gap 0.5)
				(thermal_bridge_width 0.5)
				(island_removal_mode 0)
			)
			(polygon
				(pts
					(xy 23.54834 -86.4108) (xy 23.04034 -86.4108) (xy 23.04034 -86.7918) (xy 23.54834 -86.7918)
				)
			)
		)
	)
	(footprint ""
		(layer "F.Cu")
		(at 407.753566 -96.500442 -90)
		(property "Reference" "C8C12"
			(at -0.8382 -0.67818 270)
			(unlocked yes)
			(layer "F.SilkS")
			(effects
				(font
					(size 0.4064 0.254)
					(thickness 0.1524)
				)
				(justify left)
			)
		)
		(property "Value" ""
			(at 0 0 270)
			(layer "F.Fab")
			(effects
				(font
					(size 1.27 1.27)
				)
			)
		)
		(duplicate_pad_numbers_are_jumpers no)
		(fp_poly
			(pts
				(xy 0.3048 -0.1016) (xy 0.3048 0.9906) (xy -0.3048 0.9906) (xy -0.3048 -0.1016)
			)
			(stroke
				(width 0)
				(type default)
			)
			(fill no)
			(layer "F.CrtYd")
		)
		(fp_line
			(start -0.3048 0.9906)
			(end 0.3048 0.9906)
			(stroke
				(width 0.1)
				(type default)
			)
			(layer "F.Fab")
		)
		(fp_line
			(start 0.3048 0.9906)
			(end 0.3048 -0.1016)
			(stroke
				(width 0.1)
				(type default)
			)
			(layer "F.Fab")
		)
		(fp_line
			(start -0.3048 -0.1016)
			(end -0.3048 0.9906)
			(stroke
				(width 0.1)
				(type default)
			)
			(layer "F.Fab")
		)
		(fp_line
			(start 0.3048 -0.1016)
			(end -0.3048 -0.1016)
			(stroke
				(width 0.1)
				(type default)
			)
			(layer "F.Fab")
		)
		(pad "1" smd rect
			(at 0 0 270)
			(size 0.508 0.508)
			(layers "F.Cu" "F.Mask" "F.Paste")
			(net "KR_P1_OCP_RX_DP")
		)
		(pad "2" smd rect
			(at 0 0.889 270)
			(size 0.508 0.508)
			(layers "F.Cu" "F.Mask" "F.Paste")
			(net "KR_P1_OCP_RX_C_DP")
		)
		(zone
			(layer "F.Cu")
			(hatch none 0.5)
			(connect_pads
				(clearance 0)
			)
			(min_thickness 0.25)
			(keepout
				(tracks not_allowed)
				(vias allowed)
				(pads allowed)
				(copperpour not_allowed)
				(footprints allowed)
			)
			(placement
				(enabled no)
				(sheetname "")
			)
			(fill
				(thermal_gap 0.5)
				(thermal_bridge_width 0.5)
				(island_removal_mode 0)
			)
			(polygon
				(pts
					(xy 407.118566 -96.754442) (xy 407.118566 -96.246442) (xy 407.499566 -96.246442) (xy 407.499566 -96.754442)
				)
			)
		)
		(zone
			(layer "F.Cu")
			(hatch none 0.5)
			(connect_pads
				(clearance 0)
			)
			(min_thickness 0.25)
			(keepout
				(tracks allowed)
				(vias not_allowed)
				(pads allowed)
				(copperpour not_allowed)
				(footprints allowed)
			)
			(placement
				(enabled no)
				(sheetname "")
			)
			(fill
				(thermal_gap 0.5)
				(thermal_bridge_width 0.5)
				(island_removal_mode 0)
			)
			(polygon
				(pts
					(xy 407.499566 -96.754442) (xy 407.499566 -96.246442) (xy 407.118566 -96.246442) (xy 407.118566 -96.754442)
				)
			)
		)
	)
	(footprint ""
		(layer "F.Cu")
		(at 13.8938 -35.687 90)
		(property "Reference" "C1F3"
			(at 0 0 90)
			(layer "F.SilkS")
			(hide yes)
			(effects
				(font
					(size 1.27 1.27)
				)
			)
		)
		(property "Value" ""
			(at 0 0 90)
			(layer "F.Fab")
			(effects
				(font
					(size 1.27 1.27)
				)
			)
		)
		(duplicate_pad_numbers_are_jumpers no)
		(fp_rect
			(start -0.3048 -0.1016)
			(end 0.3048 0.9906)
			(stroke
				(width 0)
				(type default)
			)
			(fill no)
			(layer "F.CrtYd")
		)
		(fp_line
			(start 0.3048 -0.1016)
			(end -0.3048 -0.1016)
			(stroke
				(width 0.1)
				(type default)
			)
			(layer "F.Fab")
		)
		(fp_line
			(start -0.3048 -0.1016)
			(end -0.3048 0.9906)
			(stroke
				(width 0.1)
				(type default)
			)
			(layer "F.Fab")
		)
		(fp_line
			(start 0.3048 0.9906)
			(end 0.3048 -0.1016)
			(stroke
				(width 0.1)
				(type default)
			)
			(layer "F.Fab")
		)
		(fp_line
			(start -0.3048 0.9906)
			(end 0.3048 0.9906)
			(stroke
				(width 0.1)
				(type default)
			)
			(layer "F.Fab")
		)
		(pad "1" smd rect
			(at 0 0 90)
			(size 0.508 0.508)
			(layers "F.Cu" "F.Mask" "F.Paste")
			(net "P3E_CPU1_PE3_MP_C_TXN<7>")
		)
		(pad "2" smd rect
			(at 0 0.889 90)
			(size 0.508 0.508)
			(layers "F.Cu" "F.Mask" "F.Paste")
			(net "P3E_CPU1_PE3_MP_TXN<7>")
		)
		(zone
			(layer "F.Cu")
			(hatch none 0.5)
			(connect_pads
				(clearance 0)
			)
			(min_thickness 0.25)
			(keepout
				(tracks not_allowed)
				(vias allowed)
				(pads allowed)
				(copperpour not_allowed)
				(footprints allowed)
			)
			(placement
				(enabled no)
				(sheetname "")
			)
			(fill
				(thermal_gap 0.5)
				(thermal_bridge_width 0.5)
				(island_removal_mode 0)
			)
			(polygon
				(pts
					(xy 14.1478 -35.433) (xy 14.5288 -35.433) (xy 14.5288 -35.941) (xy 14.1478 -35.941)
				)
			)
		)
		(zone
			(layer "F.Cu")
			(hatch none 0.5)
			(connect_pads
				(clearance 0)
			)
			(min_thickness 0.25)
			(keepout
				(tracks allowed)
				(vias not_allowed)
				(pads allowed)
				(copperpour not_allowed)
				(footprints allowed)
			)
			(placement
				(enabled no)
				(sheetname "")
			)
			(fill
				(thermal_gap 0.5)
				(thermal_bridge_width 0.5)
				(island_removal_mode 0)
			)
			(polygon
				(pts
					(xy 14.1478 -35.433) (xy 14.5288 -35.433) (xy 14.5288 -35.941) (xy 14.1478 -35.941)
				)
			)
		)
	)
	(footprint ""
		(layer "F.Cu")
		(at 489.19892 -120.75922 90)
		(property "Reference" "R9B8"
			(at 0 0 90)
			(layer "F.SilkS")
			(hide yes)
			(effects
				(font
					(size 1.27 1.27)
				)
			)
		)
		(property "Value" ""
			(at 0 0 90)
			(layer "F.Fab")
			(effects
				(font
					(size 1.27 1.27)
				)
			)
		)
		(duplicate_pad_numbers_are_jumpers no)
		(fp_rect
			(start -0.2794 -0.1016)
			(end 0.2794 0.9906)
			(stroke
				(width 0)
				(type default)
			)
			(fill no)
			(layer "F.CrtYd")
		)
		(fp_line
			(start 0.2794 -0.1016)
			(end -0.2794 -0.1016)
			(stroke
				(width 0.1)
				(type default)
			)
			(layer "F.Fab")
		)
		(fp_line
			(start -0.2794 -0.1016)
			(end -0.2794 0.9906)
			(stroke
				(width 0.1)
				(type default)
			)
			(layer "F.Fab")
		)
		(fp_line
			(start 0.2794 0.9906)
			(end 0.2794 -0.1016)
			(stroke
				(width 0.1)
				(type default)
			)
			(layer "F.Fab")
		)
		(fp_line
			(start -0.2794 0.9906)
			(end 0.2794 0.9906)
			(stroke
				(width 0.1)
				(type default)
			)
			(layer "F.Fab")
		)
		(pad "1" smd rect
			(at 0 0 90)
			(size 0.508 0.508)
			(layers "F.Cu" "F.Mask" "F.Paste")
			(net "PD_TMP421_1_A0")
		)
		(pad "2" smd rect
			(at 0 0.889 90)
			(size 0.508 0.508)
			(layers "F.Cu" "F.Mask" "F.Paste")
			(net "GND")
		)
		(zone
			(layer "F.Cu")
			(hatch none 0.5)
			(connect_pads
				(clearance 0)
			)
			(min_thickness 0.25)
			(keepout
				(tracks allowed)
				(vias not_allowed)
				(pads allowed)
				(copperpour not_allowed)
				(footprints allowed)
			)
			(placement
				(enabled no)
				(sheetname "")
			)
			(fill
				(thermal_gap 0.5)
				(thermal_bridge_width 0.5)
				(island_removal_mode 0)
			)
			(polygon
				(pts
					(xy 489.45292 -120.50522) (xy 489.83392 -120.50522) (xy 489.83392 -121.01322) (xy 489.45292 -121.01322)
				)
			)
		)
		(zone
			(layer "F.Cu")
			(hatch none 0.5)
			(connect_pads
				(clearance 0)
			)
			(min_thickness 0.25)
			(keepout
				(tracks not_allowed)
				(vias allowed)
				(pads allowed)
				(copperpour not_allowed)
				(footprints allowed)
			)
			(placement
				(enabled no)
				(sheetname "")
			)
			(fill
				(thermal_gap 0.5)
				(thermal_bridge_width 0.5)
				(island_removal_mode 0)
			)
			(polygon
				(pts
					(xy 489.45292 -120.50522) (xy 489.83392 -120.50522) (xy 489.83392 -121.01322) (xy 489.45292 -121.01322)
				)
			)
		)
	)
	(footprint ""
		(layer "F.Cu")
		(at 169.51833 -133.705092 90)
		(property "Reference" "C4B15"
			(at 0 0 90)
			(layer "F.SilkS")
			(hide yes)
			(effects
				(font
					(size 1.27 1.27)
				)
			)
		)
		(property "Value" ""
			(at 0 0 90)
			(layer "F.Fab")
			(effects
				(font
					(size 1.27 1.27)
				)
			)
		)
		(duplicate_pad_numbers_are_jumpers no)
		(fp_poly
			(pts
				(xy -0.4953 -0.2032) (xy 0.4953 -0.2032) (xy 0.4953 1.6002) (xy -0.4953 1.6002)
			)
			(stroke
				(width 0)
				(type default)
			)
			(fill no)
			(layer "F.CrtYd")
		)
		(fp_line
			(start 0.4953 -0.2032)
			(end 0.4953 1.6002)
			(stroke
				(width 0.1)
				(type default)
			)
			(layer "F.Fab")
		)
		(fp_line
			(start -0.4953 -0.2032)
			(end 0.4953 -0.2032)
			(stroke
				(width 0.1)
				(type default)
			)
			(layer "F.Fab")
		)
		(fp_line
			(start 0.4953 1.6002)
			(end -0.4953 1.6002)
			(stroke
				(width 0.1)
				(type default)
			)
			(layer "F.Fab")
		)
		(fp_line
			(start -0.4953 1.6002)
			(end -0.4953 -0.2032)
			(stroke
				(width 0.1)
				(type default)
			)
			(layer "F.Fab")
		)
		(pad "1" smd rect
			(at 0 0 90)
			(size 0.762 0.889)
			(layers "F.Cu" "F.Mask" "F.Paste")
			(net "VR_PVPP_KLM_PHASE")
		)
		(pad "2" smd rect
			(at 0 1.397 90)
			(size 0.762 0.889)
			(layers "F.Cu" "F.Mask" "F.Paste")
			(net "VR_PVPP_KLM_BOOT_R")
		)
		(zone
			(layer "F.Cu")
			(hatch none 0.5)
			(connect_pads
				(clearance 0)
			)
			(min_thickness 0.25)
			(keepout
				(tracks not_allowed)
				(vias allowed)
				(pads allowed)
				(copperpour not_allowed)
				(footprints allowed)
			)
			(placement
				(enabled no)
				(sheetname "")
			)
			(fill
				(thermal_gap 0.5)
				(thermal_bridge_width 0.5)
				(island_removal_mode 0)
			)
			(polygon
				(pts
					(xy 169.96283 -133.324092) (xy 169.96283 -134.086092) (xy 170.47083 -134.086092) (xy 170.47083 -133.324092)
				)
			)
		)
	)
)
